# T6G (Grand Teton) — schematic netlist excerpt (pin names and nets, part order shuffled) for the footprints in the layout excerpt that follows; sources: Cadence DE-HDL packaged netlist, KiCad conversion of 04192023_DAF0TMB3IC0_F0TG_MB_C_brd_V02_OCP.brd

PU39  ISL99390FRZTR5935  ISL99390FRZ-TR5935 IC  pkg QFN21_6X5XB  page 222
  VOS  = PVDDIO_P1_VOS1
  AGND  = GND
  VCC  = PVDDIO_P1_VCC1
  PVCC  = PVDDCR_CPU1_P1_PVCC
  PGND1  = GND
  GL1  = NC_PVDDIO_P1_GL1_1
  PGND2  = GND
  SW  = SW_PVDDIO_P1_SW1
  VIN1  = SW_P12V_AUX_PVDDIO_P1_FLT
  VIN2  = SW_P12V_AUX_PVDDIO_P1_FLT
  DNC  = NC_PVDDIO_P1_DNC1
  PHASE  = SW_PVDDIO_P1_BOOTR1
  BOOT  = SW_PVDDIO_P1_BOOT1
  PWM  = PVDDIO_P1_PWM1
  EN  = PVDDIO_P1_VCC1
  TOUT_FLT  = PVDDIO_P1_TEMP1
  LSET  = PVDDIO_P1_LSET1
  IOUT  = PVDDIO_P1_IMON1
  REFIN  = PVDDCR_CPU1_P1_VCCS
  PGND3  = GND
  GL2  = NC_PVDDIO_P1_GL2_1

(kicad_pcb
	(version 20260206)
	(generator "pcbnew")
	(generator_version "10.0")
	(general
		(thickness 1.6)
		(legacy_teardrops no)
	)
	(paper "A4")
	(title_block
		(title "04192023_DAF0TMB3IC0_F0TG_MB_C_brd_V02_OCP.brd")
		(comment 1 "Grand Teton / footprints 4617-4617 of 8354")
	)
	(layers
		(0 "F.Cu" signal "TOP")
		(4 "In1.Cu" signal "GND")
		(6 "In2.Cu" signal "IN1")
		(8 "In3.Cu" signal "GND1")
		(10 "In4.Cu" signal "IN2")
		(12 "In5.Cu" signal "GND2")
		(14 "In6.Cu" signal "IN3")
		(16 "In7.Cu" signal "GND3")
		(18 "In8.Cu" signal "VCC")
		(20 "In9.Cu" signal "VCC1")
		(22 "In10.Cu" signal "GND4")
		(24 "In11.Cu" signal "IN4")
		(26 "In12.Cu" signal "GND5")
		(28 "In13.Cu" signal "IN5")
		(30 "In14.Cu" signal "GND6")
		(32 "In15.Cu" signal "IN6")
		(34 "In16.Cu" signal "GND7")
		(2 "B.Cu" signal "BOTTOM")
		(9 "F.Adhes" user "F.Adhesive")
		(11 "B.Adhes" user "B.Adhesive")
		(13 "F.Paste" user "Package Geometry/Pastemask Top")
		(15 "B.Paste" user "Package Geometry/Pastemask Bottom")
		(5 "F.SilkS" user "Ref Des/Silkscreen Top")
		(7 "B.SilkS" user "Ref Des/Silkscreen Bottom")
		(1 "F.Mask" user "Board Geometry/Soldermask Top")
		(3 "B.Mask" user "Board Geometry/Soldermask Bottom")
		(17 "Dwgs.User" user "User.Drawings")
		(19 "Cmts.User" user "User.Comments")
		(21 "Eco1.User" user "User.Eco1")
		(23 "Eco2.User" user "User.Eco2")
		(25 "Edge.Cuts" user "Board Geometry/Outline")
		(27 "Margin" user)
		(31 "F.CrtYd" user "Package Geometry/Place Bound Top")
		(29 "B.CrtYd" user "Package Geometry/Place Bound Bottom")
		(35 "F.Fab" user "Ref Des/Assembly Top")
		(33 "B.Fab" user "Ref Des/Assembly Bottom")
	)
	(footprint ""
		(layer "F.Cu")
		(at 53.543454 -346.721176)
		(property "Reference" "PU39"
			(at -3.124454 -7.709154 0)
			(unlocked yes)
			(layer "F.SilkS")
			(effects
				(font
					(size 0.7874 0.5842)
					(thickness 0.1524)
				)
				(justify left)
			)
		)
		(property "Value" ""
			(at 0 0 0)
			(layer "F.Fab")
			(effects
				(font
					(size 1.27 1.27)
				)
			)
		)
		(duplicate_pad_numbers_are_jumpers no)
		(fp_line
			(start -2.500122 -2.999994)
			(end -2.24409 -2.999994)
			(stroke
				(width 0.1524)
				(type default)
			)
			(layer "F.SilkS")
		)
		(fp_line
			(start -2.500122 -2.529078)
			(end -2.500122 -2.999994)
			(stroke
				(width 0.1524)
				(type default)
			)
			(layer "F.SilkS")
		)
		(fp_line
			(start -2.500122 0.6604)
			(end -2.500122 0.229108)
			(stroke
				(width 0.1524)
				(type default)
			)
			(layer "F.SilkS")
		)
		(fp_line
			(start -2.500122 2.999994)
			(end -2.500122 2.339594)
			(stroke
				(width 0.1524)
				(type default)
			)
			(layer "F.SilkS")
		)
		(fp_line
			(start -2.2987 2.999994)
			(end -2.500122 2.999994)
			(stroke
				(width 0.1524)
				(type default)
			)
			(layer "F.SilkS")
		)
		(fp_line
			(start 2.31394 -2.999994)
			(end 2.500122 -2.999994)
			(stroke
				(width 0.1524)
				(type default)
			)
			(layer "F.SilkS")
		)
		(fp_line
			(start 2.500122 -2.999994)
			(end 2.500122 -2.44348)
			(stroke
				(width 0.1524)
				(type default)
			)
			(layer "F.SilkS")
		)
		(fp_line
			(start 2.500122 2.339594)
			(end 2.500122 2.999994)
			(stroke
				(width 0.1524)
				(type default)
			)
			(layer "F.SilkS")
		)
		(fp_line
			(start 2.500122 2.999994)
			(end 2.2987 2.999994)
			(stroke
				(width 0.1524)
				(type default)
			)
			(layer "F.SilkS")
		)
		(fp_poly
			(pts
				(xy -2.72923 -2.454148) (xy -3.402838 -2.678684) (xy -2.953766 -3.127756)
			)
			(stroke
				(width 0)
				(type default)
			)
			(fill yes)
			(layer "F.SilkS")
		)
		(fp_line
			(start -2.500122 -2.999994)
			(end 2.500122 -2.999994)
			(stroke
				(width 0.1)
				(type default)
			)
			(layer "F.Fab")
		)
		(fp_line
			(start -2.500122 2.999994)
			(end -2.500122 -2.999994)
			(stroke
				(width 0.1)
				(type default)
			)
			(layer "F.Fab")
		)
		(fp_line
			(start 2.500122 -2.999994)
			(end 2.500122 2.999994)
			(stroke
				(width 0.1)
				(type default)
			)
			(layer "F.Fab")
		)
		(fp_line
			(start 2.500122 2.999994)
			(end -2.500122 2.999994)
			(stroke
				(width 0.1)
				(type default)
			)
			(layer "F.Fab")
		)
		(fp_poly
			(pts
				(xy -4.218432 -2.783078) (xy -4.218432 -1.767078) (xy -3.202432 -2.275078)
			)
			(stroke
				(width 0)
				(type default)
			)
			(fill yes)
			(layer "F.Fab")
		)
		(pad "1" smd rect
			(at -2.400046 -2.275078 90)
			(size 0.2286 0.6096)
			(layers "F.Cu" "F.Mask" "F.Paste")
			(net "PVDDIO_P1_VOS1")
		)
		(pad "2" smd rect
			(at -2.400046 -1.82499 90)
			(size 0.2286 0.6096)
			(layers "F.Cu" "F.Mask" "F.Paste")
			(net "GND")
		)
		(pad "3" smd rect
			(at -2.400046 -1.374902 90)
			(size 0.2286 0.6096)
			(layers "F.Cu" "F.Mask" "F.Paste")
			(net "PVDDIO_P1_VCC1")
		)
		(pad "4" smd rect
			(at -2.400046 -0.925068 90)
			(size 0.2286 0.6096)
			(layers "F.Cu" "F.Mask" "F.Paste")
			(net "PVDDCR_CPU1_P1_PVCC")
		)
		(pad "5" smd rect
			(at -2.400046 -0.47498 90)
			(size 0.2286 0.6096)
			(layers "F.Cu" "F.Mask" "F.Paste")
			(net "GND")
		)
		(pad "6" smd rect
			(at -2.400046 -0.024892 90)
			(size 0.2286 0.6096)
			(layers "F.Cu" "F.Mask" "F.Paste")
			(net "NC_PVDDIO_P1_GL1_1")
		)
		(pad "7_9-20_24" smd circle
			(at 0 1.150112 90)
			(size 0 0)
			(layers "F.Cu" "F.Mask" "F.Paste")
			(net "GND")
		)
		(pad "10_19" smd rect
			(at 0 2.899918 90)
			(size 0.6096 4.318)
			(layers "F.Cu" "F.Mask" "F.Paste")
			(net "SW_PVDDIO_P1_SW1")
		)
		(pad "25_29" smd rect
			(at 1.549908 -1.279906 270)
			(size 2.0574 2.3114)
			(layers "F.Cu" "F.Mask" "F.Paste")
			(net "SW_P12V_AUX_PVDDIO_P1_FLT")
		)
		(pad "30" smd rect
			(at 2.05994 -2.899918)
			(size 0.2286 0.6096)
			(layers "F.Cu" "F.Mask" "F.Paste")
			(net "SW_P12V_AUX_PVDDIO_P1_FLT")
		)
		(pad "31" smd rect
			(at 1.610106 -2.899918)
			(size 0.2286 0.6096)
			(layers "F.Cu" "F.Mask" "F.Paste")
			(net "NC_PVDDIO_P1_DNC1")
		)
		(pad "32" smd rect
			(at 1.160018 -2.899918)
			(size 0.2286 0.6096)
			(layers "F.Cu" "F.Mask" "F.Paste")
			(net "SW_PVDDIO_P1_BOOTR1")
		)
		(pad "33" smd rect
			(at 0.70993 -2.899918)
			(size 0.2286 0.6096)
			(layers "F.Cu" "F.Mask" "F.Paste")
			(net "SW_PVDDIO_P1_BOOT1")
		)
		(pad "34" smd rect
			(at 0.260096 -2.899918)
			(size 0.2286 0.6096)
			(layers "F.Cu" "F.Mask" "F.Paste")
			(net "PVDDIO_P1_PWM1")
		)
		(pad "35" smd rect
			(at -0.189992 -2.899918)
			(size 0.2286 0.6096)
			(layers "F.Cu" "F.Mask" "F.Paste")
			(net "PVDDIO_P1_VCC1")
		)
		(pad "36" smd rect
			(at -0.64008 -2.899918)
			(size 0.2286 0.6096)
			(layers "F.Cu" "F.Mask" "F.Paste")
			(net "PVDDIO_P1_TEMP1")
		)
		(pad "37" smd rect
			(at -1.089914 -2.899918)
			(size 0.2286 0.6096)
			(layers "F.Cu" "F.Mask" "F.Paste")
			(net "PVDDIO_P1_LSET1")
		)
		(pad "38" smd rect
			(at -1.540002 -2.899918)
			(size 0.2286 0.6096)
			(layers "F.Cu" "F.Mask" "F.Paste")
			(net "PVDDIO_P1_IMON1")
		)
		(pad "39" smd rect
			(at -1.99009 -2.899918)
			(size 0.2286 0.6096)
			(layers "F.Cu" "F.Mask" "F.Paste")
			(net "PVDDCR_CPU1_P1_VCCS")
		)
		(pad "40" smd rect
			(at -0.87503 -1.27508)
			(size 1.7526 1.9558)
			(layers "F.Cu" "F.Mask" "F.Paste")
			(net "GND")
		)
		(pad "41" smd rect
			(at -1.525016 0.249936 270)
			(size 0.3048 0.4572)
			(layers "F.Cu" "F.Mask" "F.Paste")
			(net "NC_PVDDIO_P1_GL2_1")
		)
		(zone
			(layer "F.Cu")
			(hatch none 0.5)
			(connect_pads
				(clearance 0)
			)
			(min_thickness 0.25)
			(keepout
				(tracks not_allowed)
				(vias allowed)
				(pads allowed)
				(copperpour not_allowed)
				(footprints allowed)
			)
			(placement
				(enabled no)
				(sheetname "")
			)
			(fill
				(thermal_gap 0.5)
				(thermal_bridge_width 0.5)
				(island_removal_mode 0)
			)
			(polygon
				(pts
					(xy 51.043332 -344.156284) (xy 51.043332 -344.470482) (xy 56.043576 -344.470482) (xy 56.043576 -344.138758)
					(xy 55.753254 -344.138758) (xy 55.753254 -344.176858) (xy 51.333654 -344.176858) (xy 51.333654 -344.156284)
				)
			)
		)
		(zone
			(layer "F.Cu")
			(hatch none 0.5)
			(connect_pads
				(clearance 0)
			)
			(min_thickness 0.25)
			(keepout
				(tracks not_allowed)
				(vias allowed)
				(pads allowed)
				(copperpour not_allowed)
				(footprints allowed)
			)
			(placement
				(enabled no)
				(sheetname "")
			)
			(fill
				(thermal_gap 0.5)
				(thermal_bridge_width 0.5)
				(island_removal_mode 0)
			)
			(polygon
				(pts
					(xy 53.595524 -346.967556) (xy 53.595524 -349.024956) (xy 51.741324 -349.024956) (xy 51.741324 -348.78391)
					(xy 51.499008 -348.78391) (xy 51.499008 -349.265494) (xy 55.350664 -349.265494) (xy 55.350664 -349.080582)
					(xy 53.886862 -349.080582) (xy 53.886862 -346.921582) (xy 56.043576 -346.921582) (xy 56.043576 -346.6719)
					(xy 53.89118 -346.6719)
				)
			)
		)
	)
)
